(kicad_pcb
	(version 20260206)
	(generator "pcbnew")
	(generator_version "10.0")
	(general
		(thickness 1.6)
		(legacy_teardrops no)
	)
	(paper "A4")
	(title_block
		(title "01162023_DA0F0TEBIF0_F0T_Expander_BD_F_brd_V02_OCP.brd")
		(comment 1 "Grand Teton / footprint 6619 of 9728 (PEX0), pads 2118-2235 of 2397")
	)
	(layers
		(0 "F.Cu" signal "TOP")
		(4 "In1.Cu" signal "GND")
		(6 "In2.Cu" signal "VCC")
		(8 "In3.Cu" signal "VCC1")
		(10 "In4.Cu" signal "GND1")
		(12 "In5.Cu" signal "IN1")
		(14 "In6.Cu" signal "GND2")
		(16 "In7.Cu" signal "IN2")
		(18 "In8.Cu" signal "GND3")
		(20 "In9.Cu" signal "IN3")
		(22 "In10.Cu" signal "GND4")
		(24 "In11.Cu" signal "IN4")
		(26 "In12.Cu" signal "GND5")
		(28 "In13.Cu" signal "IN5")
		(30 "In14.Cu" signal "GND6")
		(32 "In15.Cu" signal "IN6")
		(34 "In16.Cu" signal "GND7")
		(2 "B.Cu" signal "BOTTOM")
		(9 "F.Adhes" user "F.Adhesive")
		(11 "B.Adhes" user "B.Adhesive")
		(13 "F.Paste" user "Package Geometry/Pastemask Top")
		(15 "B.Paste" user "Package Geometry/Pastemask Bottom")
		(5 "F.SilkS" user "Ref Des/Silkscreen Top")
		(7 "B.SilkS" user "Ref Des/Silkscreen Bottom")
		(1 "F.Mask" user "Board Geometry/Soldermask Top")
		(3 "B.Mask" user "Board Geometry/Soldermask Bottom")
		(17 "Dwgs.User" user "User.Drawings")
		(19 "Cmts.User" user "User.Comments")
		(21 "Eco1.User" user "User.Eco1")
		(23 "Eco2.User" user "User.Eco2")
		(25 "Edge.Cuts" user "Board Geometry/Outline")
		(27 "Margin" user)
		(31 "F.CrtYd" user "Package Geometry/Place Bound Top")
		(29 "B.CrtYd" user "Package Geometry/Place Bound Bottom")
		(35 "F.Fab" user "Ref Des/Assembly Top")
		(33 "B.Fab" user "Ref Des/Assembly Bottom")
	)
	(footprint ""
		(layer "F.Cu")
		(at 59.649868 -295.89984)
		(property "Reference" "PEX0"
			(at -3.360166 35.566858 0)
			(unlocked yes)
			(layer "F.SilkS")
			(effects
				(font
					(size 2.032 1.524)
					(thickness 0.1524)
				)
				(justify left)
			)
		)
		(property "Value" ""
			(at 0 0 0)
			(layer "F.Fab")
			(effects
				(font
					(size 1.27 1.27)
				)
			)
		)
		(duplicate_pad_numbers_are_jumpers no)
		(pad "R15" smd circle
			(at -9.500108 -9.500108)
			(size 0.4572 0.4572)
			(layers "F.Cu" "F.Mask" "F.Paste")
			(net "GND")
		)
		(pad "R16" smd circle
			(at -8.549894 -9.500108)
			(size 0.4572 0.4572)
			(layers "F.Cu" "F.Mask" "F.Paste")
			(net "GND")
		)
		(pad "R17" smd circle
			(at -7.599934 -9.500108)
			(size 0.4572 0.4572)
			(layers "F.Cu" "F.Mask" "F.Paste")
			(net "GND")
		)
		(pad "R18" smd circle
			(at -6.649974 -9.500108)
			(size 0.4572 0.4572)
			(layers "F.Cu" "F.Mask" "F.Paste")
			(net "GND")
		)
		(pad "R19" smd circle
			(at -5.700014 -9.500108)
			(size 0.4572 0.4572)
			(layers "F.Cu" "F.Mask" "F.Paste")
			(net "GND")
		)
		(pad "R20" smd circle
			(at -4.750054 -9.500108)
			(size 0.4572 0.4572)
			(layers "F.Cu" "F.Mask" "F.Paste")
			(net "GND")
		)
		(pad "R21" smd circle
			(at -3.800094 -9.500108)
			(size 0.4572 0.4572)
			(layers "F.Cu" "F.Mask" "F.Paste")
			(net "GND")
		)
		(pad "R22" smd circle
			(at -2.84988 -9.500108)
			(size 0.4572 0.4572)
			(layers "F.Cu" "F.Mask" "F.Paste")
			(net "GND")
		)
		(pad "R23" smd circle
			(at -1.89992 -9.500108)
			(size 0.4572 0.4572)
			(layers "F.Cu" "F.Mask" "F.Paste")
			(net "GND")
		)
		(pad "R24" smd circle
			(at -0.94996 -9.500108)
			(size 0.4572 0.4572)
			(layers "F.Cu" "F.Mask" "F.Paste")
			(net "GND")
		)
		(pad "R25" smd circle
			(at 0 -9.500108)
			(size 0.4572 0.4572)
			(layers "F.Cu" "F.Mask" "F.Paste")
			(net "GND")
		)
		(pad "R26" smd circle
			(at 0.94996 -9.500108)
			(size 0.4572 0.4572)
			(layers "F.Cu" "F.Mask" "F.Paste")
			(net "GND")
		)
		(pad "R27" smd circle
			(at 1.89992 -9.500108)
			(size 0.4572 0.4572)
			(layers "F.Cu" "F.Mask" "F.Paste")
			(net "GND")
		)
		(pad "R28" smd circle
			(at 2.84988 -9.500108)
			(size 0.4572 0.4572)
			(layers "F.Cu" "F.Mask" "F.Paste")
			(net "GND")
		)
		(pad "R29" smd circle
			(at 3.800094 -9.500108)
			(size 0.4572 0.4572)
			(layers "F.Cu" "F.Mask" "F.Paste")
			(net "GND")
		)
		(pad "R30" smd circle
			(at 4.750054 -9.500108)
			(size 0.4572 0.4572)
			(layers "F.Cu" "F.Mask" "F.Paste")
			(net "GND")
		)
		(pad "R31" smd circle
			(at 5.700014 -9.500108)
			(size 0.4572 0.4572)
			(layers "F.Cu" "F.Mask" "F.Paste")
			(net "GND")
		)
		(pad "R32" smd circle
			(at 6.649974 -9.500108)
			(size 0.4572 0.4572)
			(layers "F.Cu" "F.Mask" "F.Paste")
			(net "GND")
		)
		(pad "R33" smd circle
			(at 7.599934 -9.500108)
			(size 0.4572 0.4572)
			(layers "F.Cu" "F.Mask" "F.Paste")
			(net "GND")
		)
		(pad "R34" smd circle
			(at 8.549894 -9.500108)
			(size 0.4572 0.4572)
			(layers "F.Cu" "F.Mask" "F.Paste")
			(net "GND")
		)
		(pad "R35" smd circle
			(at 9.500108 -9.500108)
			(size 0.4572 0.4572)
			(layers "F.Cu" "F.Mask" "F.Paste")
			(net "GND")
		)
		(pad "R36" smd circle
			(at 10.450068 -9.500108)
			(size 0.4572 0.4572)
			(layers "F.Cu" "F.Mask" "F.Paste")
			(net "Net_488")
		)
		(pad "R37" smd circle
			(at 11.400028 -9.500108)
			(size 0.4572 0.4572)
			(layers "F.Cu" "F.Mask" "F.Paste")
			(net "GND")
		)
		(pad "R38" smd circle
			(at 12.349988 -9.500108)
			(size 0.4572 0.4572)
			(layers "F.Cu" "F.Mask" "F.Paste")
			(net "Net_2836")
		)
		(pad "R39" smd circle
			(at 13.299948 -9.500108)
			(size 0.4572 0.4572)
			(layers "F.Cu" "F.Mask" "F.Paste")
			(net "Net_2830")
		)
		(pad "R40" smd circle
			(at 14.249908 -9.500108)
			(size 0.4572 0.4572)
			(layers "F.Cu" "F.Mask" "F.Paste")
			(net "GND")
		)
		(pad "R41" smd circle
			(at 15.200122 -9.500108)
			(size 0.4572 0.4572)
			(layers "F.Cu" "F.Mask" "F.Paste")
			(net "GND")
		)
		(pad "R42" smd circle
			(at 16.150082 -9.500108)
			(size 0.4572 0.4572)
			(layers "F.Cu" "F.Mask" "F.Paste")
			(net "GND")
		)
		(pad "R43" smd circle
			(at 17.100042 -9.500108)
			(size 0.4572 0.4572)
			(layers "F.Cu" "F.Mask" "F.Paste")
			(net "P5E_PEX0_STN4_TX_DP<65>")
		)
		(pad "R44" smd circle
			(at 18.050002 -9.500108)
			(size 0.4572 0.4572)
			(layers "F.Cu" "F.Mask" "F.Paste")
			(net "P5E_PEX0_STN4_TX_DN<65>")
		)
		(pad "R45" smd circle
			(at 18.999962 -9.500108)
			(size 0.4572 0.4572)
			(layers "F.Cu" "F.Mask" "F.Paste")
			(net "GND")
		)
		(pad "R46" smd circle
			(at 19.949922 -9.500108)
			(size 0.4572 0.4572)
			(layers "F.Cu" "F.Mask" "F.Paste")
			(net "P5E_PEX0_STN4_RX_DP<65>")
		)
		(pad "R47" smd circle
			(at 20.899882 -9.500108)
			(size 0.4572 0.4572)
			(layers "F.Cu" "F.Mask" "F.Paste")
			(net "P5E_PEX0_STN4_RX_DN<65>")
		)
		(pad "R48" smd circle
			(at 21.850096 -9.500108)
			(size 0.4572 0.4572)
			(layers "F.Cu" "F.Mask" "F.Paste")
			(net "GND")
		)
		(pad "R49" smd circle
			(at 22.800056 -9.500108)
			(size 0.4572 0.4572)
			(layers "F.Cu" "F.Mask" "F.Paste")
			(net "GND")
		)
		(pad "T1" smd circle
			(at -22.800056 -8.549894)
			(size 0.4572 0.4572)
			(layers "F.Cu" "F.Mask" "F.Paste")
			(net "P5E_PEX0_STN7_RX_DN<115>")
		)
		(pad "T2" smd circle
			(at -21.850096 -8.549894)
			(size 0.4572 0.4572)
			(layers "F.Cu" "F.Mask" "F.Paste")
			(net "P5E_PEX0_STN7_RX_DP<115>")
		)
		(pad "T3" smd circle
			(at -20.899882 -8.549894)
			(size 0.4572 0.4572)
			(layers "F.Cu" "F.Mask" "F.Paste")
			(net "GND")
		)
		(pad "T4" smd circle
			(at -19.949922 -8.549894)
			(size 0.4572 0.4572)
			(layers "F.Cu" "F.Mask" "F.Paste")
			(net "GND")
		)
		(pad "T5" smd circle
			(at -18.999962 -8.549894)
			(size 0.4572 0.4572)
			(layers "F.Cu" "F.Mask" "F.Paste")
			(net "GND")
		)
		(pad "T6" smd circle
			(at -18.050002 -8.549894)
			(size 0.4572 0.4572)
			(layers "F.Cu" "F.Mask" "F.Paste")
			(net "GND")
		)
		(pad "T7" smd circle
			(at -17.100042 -8.549894)
			(size 0.4572 0.4572)
			(layers "F.Cu" "F.Mask" "F.Paste")
			(net "GND")
		)
		(pad "T8" smd circle
			(at -16.150082 -8.549894)
			(size 0.4572 0.4572)
			(layers "F.Cu" "F.Mask" "F.Paste")
			(net "P5E_PEX0_STN7_TX_DN<115>")
		)
		(pad "T9" smd circle
			(at -15.200122 -8.549894)
			(size 0.4572 0.4572)
			(layers "F.Cu" "F.Mask" "F.Paste")
			(net "P5E_PEX0_STN7_TX_DP<115>")
		)
		(pad "T10" smd circle
			(at -14.249908 -8.549894)
			(size 0.4572 0.4572)
			(layers "F.Cu" "F.Mask" "F.Paste")
			(net "GND")
		)
		(pad "T11" smd circle
			(at -13.299948 -8.549894)
			(size 0.4572 0.4572)
			(layers "F.Cu" "F.Mask" "F.Paste")
			(net "GND")
		)
		(pad "T12" smd circle
			(at -12.349988 -8.549894)
			(size 0.4572 0.4572)
			(layers "F.Cu" "F.Mask" "F.Paste")
			(net "GND")
		)
		(pad "T13" smd circle
			(at -11.400028 -8.549894)
			(size 0.4572 0.4572)
			(layers "F.Cu" "F.Mask" "F.Paste")
			(net "GND")
		)
		(pad "T14" smd circle
			(at -10.450068 -8.549894)
			(size 0.4572 0.4572)
			(layers "F.Cu" "F.Mask" "F.Paste")
			(net "Net_489")
		)
		(pad "T15" smd circle
			(at -9.500108 -8.549894)
			(size 0.4572 0.4572)
			(layers "F.Cu" "F.Mask" "F.Paste")
			(net "GND")
		)
		(pad "T16" smd circle
			(at -8.549894 -8.549894)
			(size 0.4572 0.4572)
			(layers "F.Cu" "F.Mask" "F.Paste")
			(net "P1V25_SERDES_VDDPLL_PEX0")
		)
		(pad "T17" smd circle
			(at -7.599934 -8.549894)
			(size 0.4572 0.4572)
			(layers "F.Cu" "F.Mask" "F.Paste")
			(net "P1V25_SERDES_VDDPLL_PEX0")
		)
		(pad "T18" smd circle
			(at -6.649974 -8.549894)
			(size 0.4572 0.4572)
			(layers "F.Cu" "F.Mask" "F.Paste")
			(net "P1V25_SERDES_VDDPLL_PEX0")
		)
		(pad "T19" smd circle
			(at -5.700014 -8.549894)
			(size 0.4572 0.4572)
			(layers "F.Cu" "F.Mask" "F.Paste")
			(net "P1V25_SERDES_VDDPLL_PEX0")
		)
		(pad "T20" smd circle
			(at -4.750054 -8.549894)
			(size 0.4572 0.4572)
			(layers "F.Cu" "F.Mask" "F.Paste")
			(net "P1V25_SERDES_VDDPLL_PEX0")
		)
		(pad "T21" smd circle
			(at -3.800094 -8.549894)
			(size 0.4572 0.4572)
			(layers "F.Cu" "F.Mask" "F.Paste")
			(net "P1V25_SERDES_VDDPLL_PEX0")
		)
		(pad "T22" smd circle
			(at -2.84988 -8.549894)
			(size 0.4572 0.4572)
			(layers "F.Cu" "F.Mask" "F.Paste")
			(net "P1V25_SERDES_VDDPLL_PEX0")
		)
		(pad "T23" smd circle
			(at -1.89992 -8.549894)
			(size 0.4572 0.4572)
			(layers "F.Cu" "F.Mask" "F.Paste")
			(net "P1V25_SERDES_VDDPLL_PEX0")
		)
		(pad "T24" smd circle
			(at -0.94996 -8.549894)
			(size 0.4572 0.4572)
			(layers "F.Cu" "F.Mask" "F.Paste")
			(net "P1V25_SERDES_VDDPLL_PEX0")
		)
		(pad "T25" smd circle
			(at 0 -8.549894)
			(size 0.4572 0.4572)
			(layers "F.Cu" "F.Mask" "F.Paste")
			(net "P1V25_SERDES_VDDPLL_PEX0")
		)
		(pad "T26" smd circle
			(at 0.94996 -8.549894)
			(size 0.4572 0.4572)
			(layers "F.Cu" "F.Mask" "F.Paste")
			(net "P1V25_SERDES_VDDPLL_PEX0")
		)
		(pad "T27" smd circle
			(at 1.89992 -8.549894)
			(size 0.4572 0.4572)
			(layers "F.Cu" "F.Mask" "F.Paste")
			(net "P1V25_SERDES_VDDPLL_PEX0")
		)
		(pad "T28" smd circle
			(at 2.84988 -8.549894)
			(size 0.4572 0.4572)
			(layers "F.Cu" "F.Mask" "F.Paste")
			(net "P1V25_SERDES_VDDPLL_PEX0")
		)
		(pad "T29" smd circle
			(at 3.800094 -8.549894)
			(size 0.4572 0.4572)
			(layers "F.Cu" "F.Mask" "F.Paste")
			(net "P1V25_SERDES_VDDPLL_PEX0")
		)
		(pad "T30" smd circle
			(at 4.750054 -8.549894)
			(size 0.4572 0.4572)
			(layers "F.Cu" "F.Mask" "F.Paste")
			(net "P1V25_SERDES_VDDPLL_PEX0")
		)
		(pad "T31" smd circle
			(at 5.700014 -8.549894)
			(size 0.4572 0.4572)
			(layers "F.Cu" "F.Mask" "F.Paste")
			(net "P1V25_SERDES_VDDPLL_PEX0")
		)
		(pad "T32" smd circle
			(at 6.649974 -8.549894)
			(size 0.4572 0.4572)
			(layers "F.Cu" "F.Mask" "F.Paste")
			(net "P1V25_SERDES_VDDPLL_PEX0")
		)
		(pad "T33" smd circle
			(at 7.599934 -8.549894)
			(size 0.4572 0.4572)
			(layers "F.Cu" "F.Mask" "F.Paste")
			(net "P1V25_SERDES_VDDPLL_PEX0")
		)
		(pad "T34" smd circle
			(at 8.549894 -8.549894)
			(size 0.4572 0.4572)
			(layers "F.Cu" "F.Mask" "F.Paste")
			(net "GND")
		)
		(pad "T35" smd circle
			(at 9.500108 -8.549894)
			(size 0.4572 0.4572)
			(layers "F.Cu" "F.Mask" "F.Paste")
			(net "P1V8_VDDA_PEX0")
		)
		(pad "T36" smd circle
			(at 10.450068 -8.549894)
			(size 0.4572 0.4572)
			(layers "F.Cu" "F.Mask" "F.Paste")
			(net "Net_479")
		)
		(pad "T37" smd circle
			(at 11.400028 -8.549894)
			(size 0.4572 0.4572)
			(layers "F.Cu" "F.Mask" "F.Paste")
			(net "GND")
		)
		(pad "T38" smd circle
			(at 12.349988 -8.549894)
			(size 0.4572 0.4572)
			(layers "F.Cu" "F.Mask" "F.Paste")
			(net "RST_PEX0_S0_PERST_R_N")
		)
		(pad "T39" smd circle
			(at 13.299948 -8.549894)
			(size 0.4572 0.4572)
			(layers "F.Cu" "F.Mask" "F.Paste")
			(net "Net_390")
		)
		(pad "T40" smd circle
			(at 14.249908 -8.549894)
			(size 0.4572 0.4572)
			(layers "F.Cu" "F.Mask" "F.Paste")
			(net "GND")
		)
		(pad "T41" smd circle
			(at 15.200122 -8.549894)
			(size 0.4572 0.4572)
			(layers "F.Cu" "F.Mask" "F.Paste")
			(net "P5E_PEX0_STN4_TX_DP<64>")
		)
		(pad "T42" smd circle
			(at 16.150082 -8.549894)
			(size 0.4572 0.4572)
			(layers "F.Cu" "F.Mask" "F.Paste")
			(net "P5E_PEX0_STN4_TX_DN<64>")
		)
		(pad "T43" smd circle
			(at 17.100042 -8.549894)
			(size 0.4572 0.4572)
			(layers "F.Cu" "F.Mask" "F.Paste")
			(net "GND")
		)
		(pad "T44" smd circle
			(at 18.050002 -8.549894)
			(size 0.4572 0.4572)
			(layers "F.Cu" "F.Mask" "F.Paste")
			(net "GND")
		)
		(pad "T45" smd circle
			(at 18.999962 -8.549894)
			(size 0.4572 0.4572)
			(layers "F.Cu" "F.Mask" "F.Paste")
			(net "GND")
		)
		(pad "T46" smd circle
			(at 19.949922 -8.549894)
			(size 0.4572 0.4572)
			(layers "F.Cu" "F.Mask" "F.Paste")
			(net "GND")
		)
		(pad "T47" smd circle
			(at 20.899882 -8.549894)
			(size 0.4572 0.4572)
			(layers "F.Cu" "F.Mask" "F.Paste")
			(net "GND")
		)
		(pad "T48" smd circle
			(at 21.850096 -8.549894)
			(size 0.4572 0.4572)
			(layers "F.Cu" "F.Mask" "F.Paste")
			(net "P5E_PEX0_STN4_RX_DP<64>")
		)
		(pad "T49" smd circle
			(at 22.800056 -8.549894)
			(size 0.4572 0.4572)
			(layers "F.Cu" "F.Mask" "F.Paste")
			(net "P5E_PEX0_STN4_RX_DN<64>")
		)
		(pad "U1" smd circle
			(at -22.800056 -7.599934)
			(size 0.4572 0.4572)
			(layers "F.Cu" "F.Mask" "F.Paste")
			(net "GND")
		)
		(pad "U2" smd circle
			(at -21.850096 -7.599934)
			(size 0.4572 0.4572)
			(layers "F.Cu" "F.Mask" "F.Paste")
			(net "GND")
		)
		(pad "U3" smd circle
			(at -20.899882 -7.599934)
			(size 0.4572 0.4572)
			(layers "F.Cu" "F.Mask" "F.Paste")
			(net "P5E_PEX0_STN7_RX_DN<114>")
		)
		(pad "U4" smd circle
			(at -19.949922 -7.599934)
			(size 0.4572 0.4572)
			(layers "F.Cu" "F.Mask" "F.Paste")
			(net "P5E_PEX0_STN7_RX_DP<114>")
		)
		(pad "U5" smd circle
			(at -18.999962 -7.599934)
			(size 0.4572 0.4572)
			(layers "F.Cu" "F.Mask" "F.Paste")
			(net "GND")
		)
		(pad "U6" smd circle
			(at -18.050002 -7.599934)
			(size 0.4572 0.4572)
			(layers "F.Cu" "F.Mask" "F.Paste")
			(net "P5E_PEX0_STN7_TX_DN<114>")
		)
		(pad "U7" smd circle
			(at -17.100042 -7.599934)
			(size 0.4572 0.4572)
			(layers "F.Cu" "F.Mask" "F.Paste")
			(net "P5E_PEX0_STN7_TX_DP<114>")
		)
		(pad "U8" smd circle
			(at -16.150082 -7.599934)
			(size 0.4572 0.4572)
			(layers "F.Cu" "F.Mask" "F.Paste")
			(net "GND")
		)
		(pad "U9" smd circle
			(at -15.200122 -7.599934)
			(size 0.4572 0.4572)
			(layers "F.Cu" "F.Mask" "F.Paste")
			(net "GND")
		)
		(pad "U10" smd circle
			(at -14.249908 -7.599934)
			(size 0.4572 0.4572)
			(layers "F.Cu" "F.Mask" "F.Paste")
			(net "GND")
		)
		(pad "U11" smd circle
			(at -13.299948 -7.599934)
			(size 0.4572 0.4572)
			(layers "F.Cu" "F.Mask" "F.Paste")
			(net "GND")
		)
		(pad "U12" smd circle
			(at -12.349988 -7.599934)
			(size 0.4572 0.4572)
			(layers "F.Cu" "F.Mask" "F.Paste")
			(net "GND")
		)
		(pad "U13" smd circle
			(at -11.400028 -7.599934)
			(size 0.4572 0.4572)
			(layers "F.Cu" "F.Mask" "F.Paste")
			(net "GND")
		)
		(pad "U14" smd circle
			(at -10.450068 -7.599934)
			(size 0.4572 0.4572)
			(layers "F.Cu" "F.Mask" "F.Paste")
			(net "Net_487")
		)
		(pad "U15" smd circle
			(at -9.500108 -7.599934)
			(size 0.4572 0.4572)
			(layers "F.Cu" "F.Mask" "F.Paste")
			(net "GND")
		)
		(pad "U16" smd circle
			(at -8.549894 -7.599934)
			(size 0.4572 0.4572)
			(layers "F.Cu" "F.Mask" "F.Paste")
			(net "GND")
		)
		(pad "U17" smd circle
			(at -7.599934 -7.599934)
			(size 0.4572 0.4572)
			(layers "F.Cu" "F.Mask" "F.Paste")
			(net "GND")
		)
		(pad "U18" smd circle
			(at -6.649974 -7.599934)
			(size 0.4572 0.4572)
			(layers "F.Cu" "F.Mask" "F.Paste")
			(net "GND")
		)
		(pad "U19" smd circle
			(at -5.700014 -7.599934)
			(size 0.4572 0.4572)
			(layers "F.Cu" "F.Mask" "F.Paste")
			(net "GND")
		)
		(pad "U20" smd circle
			(at -4.750054 -7.599934)
			(size 0.4572 0.4572)
			(layers "F.Cu" "F.Mask" "F.Paste")
			(net "GND")
		)
		(pad "U21" smd circle
			(at -3.800094 -7.599934)
			(size 0.4572 0.4572)
			(layers "F.Cu" "F.Mask" "F.Paste")
			(net "GND")
		)
		(pad "U22" smd circle
			(at -2.84988 -7.599934)
			(size 0.4572 0.4572)
			(layers "F.Cu" "F.Mask" "F.Paste")
			(net "GND")
		)
		(pad "U23" smd circle
			(at -1.89992 -7.599934)
			(size 0.4572 0.4572)
			(layers "F.Cu" "F.Mask" "F.Paste")
			(net "GND")
		)
		(pad "U24" smd circle
			(at -0.94996 -7.599934)
			(size 0.4572 0.4572)
			(layers "F.Cu" "F.Mask" "F.Paste")
			(net "GND")
		)
		(pad "U25" smd circle
			(at 0 -7.599934)
			(size 0.4572 0.4572)
			(layers "F.Cu" "F.Mask" "F.Paste")
			(net "GND")
		)
		(pad "U26" smd circle
			(at 0.94996 -7.599934)
			(size 0.4572 0.4572)
			(layers "F.Cu" "F.Mask" "F.Paste")
			(net "GND")
		)
		(pad "U27" smd circle
			(at 1.89992 -7.599934)
			(size 0.4572 0.4572)
			(layers "F.Cu" "F.Mask" "F.Paste")
			(net "GND")
		)
		(pad "U28" smd circle
			(at 2.84988 -7.599934)
			(size 0.4572 0.4572)
			(layers "F.Cu" "F.Mask" "F.Paste")
			(net "GND")
		)
		(pad "U29" smd circle
			(at 3.800094 -7.599934)
			(size 0.4572 0.4572)
			(layers "F.Cu" "F.Mask" "F.Paste")
			(net "GND")
		)
		(pad "U30" smd circle
			(at 4.750054 -7.599934)
			(size 0.4572 0.4572)
			(layers "F.Cu" "F.Mask" "F.Paste")
			(net "GND")
		)
		(pad "U31" smd circle
			(at 5.700014 -7.599934)
			(size 0.4572 0.4572)
			(layers "F.Cu" "F.Mask" "F.Paste")
			(net "GND")
		)
		(pad "U32" smd circle
			(at 6.649974 -7.599934)
			(size 0.4572 0.4572)
			(layers "F.Cu" "F.Mask" "F.Paste")
			(net "GND")
		)
		(pad "U33" smd circle
			(at 7.599934 -7.599934)
			(size 0.4572 0.4572)
			(layers "F.Cu" "F.Mask" "F.Paste")
			(net "GND")
		)
		(pad "U34" smd circle
			(at 8.549894 -7.599934)
			(size 0.4572 0.4572)
			(layers "F.Cu" "F.Mask" "F.Paste")
			(net "GND")
		)
	)
)
